# S9S_MB_2U (Grand Teton) — schematic netlist excerpt (pin names and nets, part order shuffled) for the footprints in the layout excerpt that follows; sources: Cadence DE-HDL packaged netlist, KiCad conversion of 03242023_DA0F0TMBIJ0_F0T_Motherboard_J_brd_V01_OCP.brd

R932  Q_RES  10K 1% CHIP  pkg 0402LF  page 128 : A = RST_CPU0_DRAM_AB_N ; B = GND
R3563  Q_RES  0 5% CHIP  pkg 0402LF  page 171 : A = OCP_SFF_P3V3_ADC_ALERT_R ; B = OCP_SFF_P3V3_ADC_ALERT

(kicad_pcb
	(version 20260206)
	(generator "pcbnew")
	(generator_version "10.0")
	(general
		(thickness 1.6)
		(legacy_teardrops no)
	)
	(paper "A4")
	(title_block
		(title "03242023_DA0F0TMBIJ0_F0T_Motherboard_J_brd_V01_OCP.brd")
		(comment 1 "Grand Teton / footprints 517-518 of 6105")
	)
	(layers
		(0 "F.Cu" signal "TOP")
		(4 "In1.Cu" signal "GND")
		(6 "In2.Cu" signal "IN1")
		(8 "In3.Cu" signal "GND1")
		(10 "In4.Cu" signal "IN2")
		(12 "In5.Cu" signal "GND2")
		(14 "In6.Cu" signal "IN3")
		(16 "In7.Cu" signal "GND3")
		(18 "In8.Cu" signal "VCC")
		(20 "In9.Cu" signal "VCC1")
		(22 "In10.Cu" signal "GND4")
		(24 "In11.Cu" signal "IN4")
		(26 "In12.Cu" signal "GND5")
		(28 "In13.Cu" signal "IN5")
		(30 "In14.Cu" signal "GND6")
		(32 "In15.Cu" signal "IN6")
		(34 "In16.Cu" signal "GND7")
		(2 "B.Cu" signal "BOTTOM")
		(9 "F.Adhes" user "F.Adhesive")
		(11 "B.Adhes" user "B.Adhesive")
		(13 "F.Paste" user "Package Geometry/Pastemask Top")
		(15 "B.Paste" user "Package Geometry/Pastemask Bottom")
		(5 "F.SilkS" user "Ref Des/Silkscreen Top")
		(7 "B.SilkS" user "Ref Des/Silkscreen Bottom")
		(1 "F.Mask" user "Board Geometry/Soldermask Top")
		(3 "B.Mask" user "Board Geometry/Soldermask Bottom")
		(17 "Dwgs.User" user "User.Drawings")
		(19 "Cmts.User" user "User.Comments")
		(21 "Eco1.User" user "User.Eco1")
		(23 "Eco2.User" user "User.Eco2")
		(25 "Edge.Cuts" user "Board Geometry/Outline")
		(27 "Margin" user)
		(31 "F.CrtYd" user "Package Geometry/Place Bound Top")
		(29 "B.CrtYd" user "Package Geometry/Place Bound Bottom")
		(35 "F.Fab" user "Ref Des/Assembly Top")
		(33 "B.Fab" user "Ref Des/Assembly Bottom")
	)
	(footprint ""
		(layer "F.Cu")
		(at 111.13008 -122.132598 90)
		(property "Reference" "R932"
			(at 0 0 90)
			(layer "F.SilkS")
			(hide yes)
			(effects
				(font
					(size 1.27 1.27)
				)
			)
		)
		(property "Value" ""
			(at 0 0 90)
			(layer "F.Fab")
			(effects
				(font
					(size 1.27 1.27)
				)
			)
		)
		(duplicate_pad_numbers_are_jumpers no)
		(fp_line
			(start 0.7874 -0.4064)
			(end 0.7874 0.4064)
			(stroke
				(width 0.1524)
				(type default)
			)
			(layer "F.SilkS")
		)
		(fp_line
			(start -0.7874 -0.4064)
			(end 0.7874 -0.4064)
			(stroke
				(width 0.1524)
				(type default)
			)
			(layer "F.SilkS")
		)
		(fp_line
			(start 0.7874 0.4064)
			(end -0.7874 0.4064)
			(stroke
				(width 0.1524)
				(type default)
			)
			(layer "F.SilkS")
		)
		(fp_line
			(start -0.7874 0.4064)
			(end -0.7874 -0.4064)
			(stroke
				(width 0.1524)
				(type default)
			)
			(layer "F.SilkS")
		)
		(fp_line
			(start -0.12065 -0.305054)
			(end -0.12065 -0.2794)
			(stroke
				(width 0.1)
				(type default)
			)
			(layer "F.Fab")
		)
		(fp_line
			(start -0.67945 -0.305054)
			(end -0.12065 -0.305054)
			(stroke
				(width 0.1)
				(type default)
			)
			(layer "F.Fab")
		)
		(fp_line
			(start 0.67945 -0.3048)
			(end 0.67945 0.3048)
			(stroke
				(width 0.1)
				(type default)
			)
			(layer "F.Fab")
		)
		(fp_line
			(start 0.12065 -0.3048)
			(end 0.67945 -0.3048)
			(stroke
				(width 0.1)
				(type default)
			)
			(layer "F.Fab")
		)
		(fp_line
			(start 0.12065 -0.2794)
			(end 0.12065 -0.3048)
			(stroke
				(width 0.1)
				(type default)
			)
			(layer "F.Fab")
		)
		(fp_line
			(start -0.12065 -0.2794)
			(end 0.12065 -0.2794)
			(stroke
				(width 0.1)
				(type default)
			)
			(layer "F.Fab")
		)
		(fp_line
			(start 0.120396 0.2794)
			(end -0.12065 0.2794)
			(stroke
				(width 0.1)
				(type default)
			)
			(layer "F.Fab")
		)
		(fp_line
			(start -0.12065 0.2794)
			(end -0.12065 0.3048)
			(stroke
				(width 0.1)
				(type default)
			)
			(layer "F.Fab")
		)
		(fp_line
			(start 0.67945 0.3048)
			(end 0.120396 0.3048)
			(stroke
				(width 0.1)
				(type default)
			)
			(layer "F.Fab")
		)
		(fp_line
			(start 0.120396 0.3048)
			(end 0.120396 0.2794)
			(stroke
				(width 0.1)
				(type default)
			)
			(layer "F.Fab")
		)
		(fp_line
			(start -0.12065 0.3048)
			(end -0.67945 0.3048)
			(stroke
				(width 0.1)
				(type default)
			)
			(layer "F.Fab")
		)
		(fp_line
			(start -0.67945 0.3048)
			(end -0.67945 -0.305054)
			(stroke
				(width 0.1)
				(type default)
			)
			(layer "F.Fab")
		)
		(pad "1" smd circle
			(at -0.40005 0 90)
			(size 0 0)
			(layers "F.Cu" "F.Mask" "F.Paste")
			(net "RST_CPU0_DRAM_AB_N")
		)
		(pad "2" smd circle
			(at 0.40005 0 90)
			(size 0 0)
			(layers "F.Cu" "F.Mask" "F.Paste")
			(net "GND")
		)
	)
	(footprint ""
		(layer "F.Cu")
		(at 445.19088 -94.602808)
		(property "Reference" "R3563"
			(at 0 0 0)
			(layer "F.SilkS")
			(hide yes)
			(effects
				(font
					(size 1.27 1.27)
				)
			)
		)
		(property "Value" ""
			(at 0 0 0)
			(layer "F.Fab")
			(effects
				(font
					(size 1.27 1.27)
				)
			)
		)
		(duplicate_pad_numbers_are_jumpers no)
		(fp_line
			(start -0.7874 -0.4064)
			(end 0.7874 -0.4064)
			(stroke
				(width 0.1524)
				(type default)
			)
			(layer "F.SilkS")
		)
		(fp_line
			(start -0.7874 0.4064)
			(end -0.7874 -0.4064)
			(stroke
				(width 0.1524)
				(type default)
			)
			(layer "F.SilkS")
		)
		(fp_line
			(start 0.7874 -0.4064)
			(end 0.7874 0.4064)
			(stroke
				(width 0.1524)
				(type default)
			)
			(layer "F.SilkS")
		)
		(fp_line
			(start 0.7874 0.4064)
			(end -0.7874 0.4064)
			(stroke
				(width 0.1524)
				(type default)
			)
			(layer "F.SilkS")
		)
		(fp_line
			(start -0.67945 -0.305054)
			(end -0.12065 -0.305054)
			(stroke
				(width 0.1)
				(type default)
			)
			(layer "F.Fab")
		)
		(fp_line
			(start -0.67945 0.3048)
			(end -0.67945 -0.305054)
			(stroke
				(width 0.1)
				(type default)
			)
			(layer "F.Fab")
		)
		(fp_line
			(start -0.12065 -0.305054)
			(end -0.12065 -0.2794)
			(stroke
				(width 0.1)
				(type default)
			)
			(layer "F.Fab")
		)
		(fp_line
			(start -0.12065 -0.2794)
			(end 0.12065 -0.2794)
			(stroke
				(width 0.1)
				(type default)
			)
			(layer "F.Fab")
		)
		(fp_line
			(start -0.12065 0.2794)
			(end -0.12065 0.3048)
			(stroke
				(width 0.1)
				(type default)
			)
			(layer "F.Fab")
		)
		(fp_line
			(start -0.12065 0.3048)
			(end -0.67945 0.3048)
			(stroke
				(width 0.1)
				(type default)
			)
			(layer "F.Fab")
		)
		(fp_line
			(start 0.120396 0.2794)
			(end -0.12065 0.2794)
			(stroke
				(width 0.1)
				(type default)
			)
			(layer "F.Fab")
		)
		(fp_line
			(start 0.120396 0.3048)
			(end 0.120396 0.2794)
			(stroke
				(width 0.1)
				(type default)
			)
			(layer "F.Fab")
		)
		(fp_line
			(start 0.12065 -0.3048)
			(end 0.67945 -0.3048)
			(stroke
				(width 0.1)
				(type default)
			)
			(layer "F.Fab")
		)
		(fp_line
			(start 0.12065 -0.2794)
			(end 0.12065 -0.3048)
			(stroke
				(width 0.1)
				(type default)
			)
			(layer "F.Fab")
		)
		(fp_line
			(start 0.67945 -0.3048)
			(end 0.67945 0.3048)
			(stroke
				(width 0.1)
				(type default)
			)
			(layer "F.Fab")
		)
		(fp_line
			(start 0.67945 0.3048)
			(end 0.120396 0.3048)
			(stroke
				(width 0.1)
				(type default)
			)
			(layer "F.Fab")
		)
		(pad "1" smd circle
			(at -0.40005 0)
			(size 0 0)
			(layers "F.Cu" "F.Mask" "F.Paste")
			(net "OCP_SFF_P3V3_ADC_ALERT_R")
		)
		(pad "2" smd circle
			(at 0.40005 0)
			(size 0 0)
			(layers "F.Cu" "F.Mask" "F.Paste")
			(net "OCP_SFF_P3V3_ADC_ALERT")
		)
	)
)
